(kicad_pcb
	(version 20260206)
	(generator "pcbnew")
	(generator_version "10.0")
	(general
		(thickness 1.6)
		(legacy_teardrops no)
	)
	(paper "A4")
	(title_block
		(title "01162023_DA0F0TEBIF0_F0T_Expander_BD_F_brd_V02_OCP.brd")
		(comment 1 "Grand Teton / footprints 3634-3638 of 9728")
	)
	(layers
		(0 "F.Cu" signal "TOP")
		(4 "In1.Cu" signal "GND")
		(6 "In2.Cu" signal "VCC")
		(8 "In3.Cu" signal "VCC1")
		(10 "In4.Cu" signal "GND1")
		(12 "In5.Cu" signal "IN1")
		(14 "In6.Cu" signal "GND2")
		(16 "In7.Cu" signal "IN2")
		(18 "In8.Cu" signal "GND3")
		(20 "In9.Cu" signal "IN3")
		(22 "In10.Cu" signal "GND4")
		(24 "In11.Cu" signal "IN4")
		(26 "In12.Cu" signal "GND5")
		(28 "In13.Cu" signal "IN5")
		(30 "In14.Cu" signal "GND6")
		(32 "In15.Cu" signal "IN6")
		(34 "In16.Cu" signal "GND7")
		(2 "B.Cu" signal "BOTTOM")
		(9 "F.Adhes" user "F.Adhesive")
		(11 "B.Adhes" user "B.Adhesive")
		(13 "F.Paste" user "Package Geometry/Pastemask Top")
		(15 "B.Paste" user "Package Geometry/Pastemask Bottom")
		(5 "F.SilkS" user "Ref Des/Silkscreen Top")
		(7 "B.SilkS" user "Ref Des/Silkscreen Bottom")
		(1 "F.Mask" user "Board Geometry/Soldermask Top")
		(3 "B.Mask" user "Board Geometry/Soldermask Bottom")
		(17 "Dwgs.User" user "User.Drawings")
		(19 "Cmts.User" user "User.Comments")
		(21 "Eco1.User" user "User.Eco1")
		(23 "Eco2.User" user "User.Eco2")
		(25 "Edge.Cuts" user "Board Geometry/Outline")
		(27 "Margin" user)
		(31 "F.CrtYd" user "Package Geometry/Place Bound Top")
		(29 "B.CrtYd" user "Package Geometry/Place Bound Bottom")
		(35 "F.Fab" user "Ref Des/Assembly Top")
		(33 "B.Fab" user "Ref Des/Assembly Bottom")
	)
	(footprint ""
		(layer "F.Cu")
		(at 422.947084 -54.3941)
		(property "Reference" "PU43"
			(at -1.670812 2.828798 0)
			(unlocked yes)
			(layer "F.SilkS")
			(effects
				(font
					(size 0.7874 0.5842)
					(thickness 0.1524)
				)
				(justify left)
			)
		)
		(property "Value" ""
			(at 0 0 0)
			(layer "F.Fab")
			(effects
				(font
					(size 1.27 1.27)
				)
			)
		)
		(duplicate_pad_numbers_are_jumpers no)
		(fp_line
			(start -1.943608 -1.549908)
			(end 1.943608 -1.549908)
			(stroke
				(width 0.1524)
				(type default)
			)
			(layer "F.SilkS")
		)
		(fp_line
			(start -1.943608 1.549908)
			(end -1.943608 -1.549908)
			(stroke
				(width 0.1524)
				(type default)
			)
			(layer "F.SilkS")
		)
		(fp_line
			(start 1.943608 -1.549908)
			(end 1.943608 1.549908)
			(stroke
				(width 0.1524)
				(type default)
			)
			(layer "F.SilkS")
		)
		(fp_line
			(start 1.943608 1.549908)
			(end -1.943608 1.549908)
			(stroke
				(width 0.1524)
				(type default)
			)
			(layer "F.SilkS")
		)
		(fp_poly
			(pts
				(xy -2.019808 -1.549908) (xy -1.257808 -1.549908) (xy -1.257808 -1.880108) (xy -2.019808 -1.880108)
			)
			(stroke
				(width 0)
				(type default)
			)
			(fill yes)
			(layer "F.SilkS")
		)
		(fp_line
			(start -1.549908 -1.549908)
			(end 1.549908 -1.549908)
			(stroke
				(width 0.1)
				(type default)
			)
			(layer "F.Fab")
		)
		(fp_line
			(start -1.549908 1.549908)
			(end -1.549908 -1.549908)
			(stroke
				(width 0.1)
				(type default)
			)
			(layer "F.Fab")
		)
		(fp_line
			(start 1.549908 -1.549908)
			(end 1.549908 1.549908)
			(stroke
				(width 0.1)
				(type default)
			)
			(layer "F.Fab")
		)
		(fp_line
			(start 1.549908 1.549908)
			(end -1.549908 1.549908)
			(stroke
				(width 0.1)
				(type default)
			)
			(layer "F.Fab")
		)
		(fp_poly
			(pts
				(xy -2.019808 -1.549908) (xy -1.257808 -1.549908) (xy -1.257808 -1.880108) (xy -2.019808 -1.880108)
			)
			(stroke
				(width 0)
				(type default)
			)
			(fill yes)
			(layer "F.Fab")
		)
		(pad "1" smd rect
			(at -1.500124 -1.249934 270)
			(size 0.2794 0.6096)
			(layers "F.Cu" "F.Mask" "F.Paste")
			(net "P12V_SSD14_R")
		)
		(pad "2" smd rect
			(at -1.500124 -0.750062 270)
			(size 0.2794 0.6096)
			(layers "F.Cu" "F.Mask" "F.Paste")
			(net "P12V_SSD14_R")
		)
		(pad "3" smd rect
			(at -1.500124 -0.249936 270)
			(size 0.2794 0.6096)
			(layers "F.Cu" "F.Mask" "F.Paste")
			(net "P12V_SSD14_R")
		)
		(pad "4" smd rect
			(at -1.500124 0.249936 270)
			(size 0.2794 0.6096)
			(layers "F.Cu" "F.Mask" "F.Paste")
			(net "P12V_SSD14_R")
		)
		(pad "5" smd rect
			(at -1.500124 0.750062 270)
			(size 0.2794 0.6096)
			(layers "F.Cu" "F.Mask" "F.Paste")
			(net "P12V_SSD14_R")
		)
		(pad "6" smd rect
			(at -1.500124 1.249934 270)
			(size 0.2794 0.6096)
			(layers "F.Cu" "F.Mask" "F.Paste")
			(net "GND")
		)
		(pad "7" smd rect
			(at 1.500124 1.249934 270)
			(size 0.2794 0.6096)
			(layers "F.Cu" "F.Mask" "F.Paste")
			(net "P12V_SSD14_SS")
		)
		(pad "8" smd rect
			(at 1.500124 0.750062 270)
			(size 0.2794 0.6096)
			(layers "F.Cu" "F.Mask" "F.Paste")
			(net "PWRGD_P12V_SSD14")
		)
		(pad "9" smd rect
			(at 1.500124 0.249936 270)
			(size 0.2794 0.6096)
			(layers "F.Cu" "F.Mask" "F.Paste")
			(net "P12V_SSD14_OCP")
		)
		(pad "10" smd rect
			(at 1.500124 -0.249936 270)
			(size 0.2794 0.6096)
			(layers "F.Cu" "F.Mask" "F.Paste")
			(net "P5V_AUX")
		)
		(pad "11" smd rect
			(at 1.500124 -0.750062 270)
			(size 0.2794 0.6096)
			(layers "F.Cu" "F.Mask" "F.Paste")
			(net "SSD14_PWR_EN_R")
		)
		(pad "12" smd rect
			(at 1.500124 -1.249934 270)
			(size 0.2794 0.6096)
			(layers "F.Cu" "F.Mask" "F.Paste")
			(net "P12V_AUX")
		)
		(pad "13" smd rect
			(at 0 0)
			(size 1.9812 2.7178)
			(layers "F.Cu" "F.Mask" "F.Paste")
			(net "P12V_AUX")
		)
		(zone
			(layer "F.Cu")
			(hatch none 0.5)
			(connect_pads
				(clearance 0)
			)
			(min_thickness 0.25)
			(keepout
				(tracks not_allowed)
				(vias allowed)
				(pads allowed)
				(copperpour not_allowed)
				(footprints allowed)
			)
			(placement
				(enabled no)
				(sheetname "")
			)
			(fill
				(thermal_gap 0.5)
				(thermal_bridge_width 0.5)
				(island_removal_mode 0)
			)
			(polygon
				(pts
					(xy 424.090084 -55.9435) (xy 424.090084 -55.8165) (xy 424.090084 -52.8447) (xy 424.090084 -52.844192)
					(xy 421.804084 -52.844192) (xy 421.804084 -52.8447) (xy 421.804084 -52.9717) (xy 421.804084 -54.3941)
					(xy 421.905684 -54.3941) (xy 421.905684 -52.9717) (xy 423.988484 -52.9717) (xy 423.988484 -55.8165)
					(xy 421.905684 -55.8165) (xy 421.905684 -54.4195) (xy 421.804084 -54.4195) (xy 421.804084 -55.8165)
					(xy 421.804084 -55.9435) (xy 421.804084 -55.944008) (xy 424.090084 -55.944008)
				)
			)
		)
	)
	(footprint ""
		(layer "F.Cu")
		(at 133.874764 -303.649634 90)
		(property "Reference" "PC120"
			(at 0 0 90)
			(layer "F.SilkS")
			(hide yes)
			(effects
				(font
					(size 1.27 1.27)
				)
			)
		)
		(property "Value" ""
			(at 0 0 90)
			(layer "F.Fab")
			(effects
				(font
					(size 1.27 1.27)
				)
			)
		)
		(duplicate_pad_numbers_are_jumpers no)
		(fp_line
			(start 1.524 -0.762)
			(end 1.524 0.762)
			(stroke
				(width 0.1524)
				(type default)
			)
			(layer "F.SilkS")
		)
		(fp_line
			(start -1.524 -0.762)
			(end 1.524 -0.762)
			(stroke
				(width 0.1524)
				(type default)
			)
			(layer "F.SilkS")
		)
		(fp_line
			(start 1.524 0.762)
			(end -1.524 0.762)
			(stroke
				(width 0.1524)
				(type default)
			)
			(layer "F.SilkS")
		)
		(fp_line
			(start -1.524 0.762)
			(end -1.524 -0.762)
			(stroke
				(width 0.1524)
				(type default)
			)
			(layer "F.SilkS")
		)
		(fp_line
			(start 1.1049 -0.724916)
			(end -1.1049 -0.724916)
			(stroke
				(width 0.1)
				(type default)
			)
			(layer "F.Fab")
		)
		(fp_line
			(start -1.1049 -0.724916)
			(end -1.1049 0.724916)
			(stroke
				(width 0.1)
				(type default)
			)
			(layer "F.Fab")
		)
		(fp_line
			(start 1.1049 0.724916)
			(end 1.1049 -0.724916)
			(stroke
				(width 0.1)
				(type default)
			)
			(layer "F.Fab")
		)
		(fp_line
			(start -1.1049 0.724916)
			(end 1.1049 0.724916)
			(stroke
				(width 0.1)
				(type default)
			)
			(layer "F.Fab")
		)
		(pad "1" smd rect
			(at -0.889 0 270)
			(size 1.016 1.27)
			(layers "F.Cu" "F.Mask" "F.Paste")
			(net "P0V8_PEX1")
		)
		(pad "2" smd rect
			(at 0.889 0 270)
			(size 1.016 1.27)
			(layers "F.Cu" "F.Mask" "F.Paste")
			(net "GND")
		)
	)
	(footprint ""
		(layer "F.Cu")
		(at 338.074 -176.911 180)
		(property "Reference" "R4755"
			(at 0 0 180)
			(layer "F.SilkS")
			(hide yes)
			(effects
				(font
					(size 1.27 1.27)
				)
			)
		)
		(property "Value" ""
			(at 0 0 180)
			(layer "F.Fab")
			(effects
				(font
					(size 1.27 1.27)
				)
			)
		)
		(duplicate_pad_numbers_are_jumpers no)
		(fp_line
			(start 0.7874 0.4064)
			(end -0.7874 0.4064)
			(stroke
				(width 0.1524)
				(type default)
			)
			(layer "F.SilkS")
		)
		(fp_line
			(start 0.7874 -0.4064)
			(end 0.7874 0.4064)
			(stroke
				(width 0.1524)
				(type default)
			)
			(layer "F.SilkS")
		)
		(fp_line
			(start -0.7874 0.4064)
			(end -0.7874 -0.4064)
			(stroke
				(width 0.1524)
				(type default)
			)
			(layer "F.SilkS")
		)
		(fp_line
			(start -0.7874 -0.4064)
			(end 0.7874 -0.4064)
			(stroke
				(width 0.1524)
				(type default)
			)
			(layer "F.SilkS")
		)
		(fp_line
			(start 0.67945 0.3048)
			(end 0.120396 0.3048)
			(stroke
				(width 0.1)
				(type default)
			)
			(layer "F.Fab")
		)
		(fp_line
			(start 0.67945 -0.3048)
			(end 0.67945 0.3048)
			(stroke
				(width 0.1)
				(type default)
			)
			(layer "F.Fab")
		)
		(fp_line
			(start 0.12065 -0.2794)
			(end 0.12065 -0.3048)
			(stroke
				(width 0.1)
				(type default)
			)
			(layer "F.Fab")
		)
		(fp_line
			(start 0.12065 -0.3048)
			(end 0.67945 -0.3048)
			(stroke
				(width 0.1)
				(type default)
			)
			(layer "F.Fab")
		)
		(fp_line
			(start 0.120396 0.3048)
			(end 0.120396 0.2794)
			(stroke
				(width 0.1)
				(type default)
			)
			(layer "F.Fab")
		)
		(fp_line
			(start 0.120396 0.2794)
			(end -0.12065 0.2794)
			(stroke
				(width 0.1)
				(type default)
			)
			(layer "F.Fab")
		)
		(fp_line
			(start -0.12065 0.3048)
			(end -0.67945 0.3048)
			(stroke
				(width 0.1)
				(type default)
			)
			(layer "F.Fab")
		)
		(fp_line
			(start -0.12065 0.2794)
			(end -0.12065 0.3048)
			(stroke
				(width 0.1)
				(type default)
			)
			(layer "F.Fab")
		)
		(fp_line
			(start -0.12065 -0.2794)
			(end 0.12065 -0.2794)
			(stroke
				(width 0.1)
				(type default)
			)
			(layer "F.Fab")
		)
		(fp_line
			(start -0.12065 -0.305054)
			(end -0.12065 -0.2794)
			(stroke
				(width 0.1)
				(type default)
			)
			(layer "F.Fab")
		)
		(fp_line
			(start -0.67945 0.3048)
			(end -0.67945 -0.305054)
			(stroke
				(width 0.1)
				(type default)
			)
			(layer "F.Fab")
		)
		(fp_line
			(start -0.67945 -0.305054)
			(end -0.12065 -0.305054)
			(stroke
				(width 0.1)
				(type default)
			)
			(layer "F.Fab")
		)
		(pad "1" smd circle
			(at -0.40005 0 180)
			(size 0 0)
			(layers "F.Cu" "F.Mask" "F.Paste")
			(net "RST_PEX_SSD9_PERST_N")
		)
		(pad "2" smd circle
			(at 0.40005 0 180)
			(size 0 0)
			(layers "F.Cu" "F.Mask" "F.Paste")
			(net "RST_PEX_SSD9_PERST_R_N")
		)
	)
	(footprint ""
		(layer "F.Cu")
		(at 369.189 -177.292)
		(property "Reference" "U346"
			(at -1.3462 -4.613148 0)
			(unlocked yes)
			(layer "F.SilkS")
			(effects
				(font
					(size 0.7874 0.5842)
					(thickness 0.1524)
				)
				(justify left)
			)
		)
		(property "Value" ""
			(at 0 0 0)
			(layer "F.Fab")
			(effects
				(font
					(size 1.27 1.27)
				)
			)
		)
		(duplicate_pad_numbers_are_jumpers no)
		(fp_line
			(start -2.097532 -3.949954)
			(end -2.097532 3.949954)
			(stroke
				(width 0.1524)
				(type default)
			)
			(layer "F.SilkS")
		)
		(fp_line
			(start -2.097532 3.949954)
			(end 2.097532 3.949954)
			(stroke
				(width 0.1524)
				(type default)
			)
			(layer "F.SilkS")
		)
		(fp_line
			(start -1.409954 -3.949954)
			(end -2.097532 -3.949954)
			(stroke
				(width 0.1524)
				(type default)
			)
			(layer "F.SilkS")
		)
		(fp_line
			(start 0 -2.54)
			(end -1.409954 -3.949954)
			(stroke
				(width 0.1524)
				(type default)
			)
			(layer "F.SilkS")
		)
		(fp_line
			(start 1.409954 -3.949954)
			(end 0 -2.54)
			(stroke
				(width 0.1524)
				(type default)
			)
			(layer "F.SilkS")
		)
		(fp_line
			(start 2.097532 -3.949954)
			(end 1.409954 -3.949954)
			(stroke
				(width 0.1524)
				(type default)
			)
			(layer "F.SilkS")
		)
		(fp_line
			(start 2.097532 3.949954)
			(end 2.097532 -3.949954)
			(stroke
				(width 0.1524)
				(type default)
			)
			(layer "F.SilkS")
		)
		(fp_poly
			(pts
				(xy -4.7498 -4.182872) (xy -4.7498 -3.166872) (xy -3.7338 -3.674872)
			)
			(stroke
				(width 0)
				(type default)
			)
			(fill yes)
			(layer "F.SilkS")
		)
		(fp_line
			(start -2.249932 -3.949954)
			(end -2.249932 3.949954)
			(stroke
				(width 0.1)
				(type default)
			)
			(layer "F.Fab")
		)
		(fp_line
			(start -2.249932 3.949954)
			(end 2.249932 3.949954)
			(stroke
				(width 0.1)
				(type default)
			)
			(layer "F.Fab")
		)
		(fp_line
			(start 2.249932 -3.949954)
			(end -2.249932 -3.949954)
			(stroke
				(width 0.1)
				(type default)
			)
			(layer "F.Fab")
		)
		(fp_line
			(start 2.249932 3.949954)
			(end 2.249932 -3.949954)
			(stroke
				(width 0.1)
				(type default)
			)
			(layer "F.Fab")
		)
		(fp_poly
			(pts
				(xy -4.7498 -4.182872) (xy -4.7498 -3.166872) (xy -3.7338 -3.674872)
			)
			(stroke
				(width 0)
				(type default)
			)
			(fill yes)
			(layer "F.Fab")
		)
		(pad "1" smd rect
			(at -2.925064 -3.674872 270)
			(size 0.6096 1.3716)
			(layers "F.Cu" "F.Mask" "F.Paste")
			(net "PEX1_PCA9555_1_INT_N")
		)
		(pad "2" smd rect
			(at -2.925064 -2.925064 270)
			(size 0.4064 1.3716)
			(layers "F.Cu" "F.Mask" "F.Paste")
			(net "PCA9555_1_PEX1_A1")
		)
		(pad "3" smd rect
			(at -2.925064 -2.275078 270)
			(size 0.4064 1.3716)
			(layers "F.Cu" "F.Mask" "F.Paste")
			(net "PCA9555_1_PEX1_A2")
		)
		(pad "4" smd rect
			(at -2.925064 -1.625092 270)
			(size 0.4064 1.3716)
			(layers "F.Cu" "F.Mask" "F.Paste")
			(net "PRSNT_SSD6_FPGA_PCA9555_N")
		)
		(pad "5" smd rect
			(at -2.925064 -0.975106 270)
			(size 0.4064 1.3716)
			(layers "F.Cu" "F.Mask" "F.Paste")
			(net "SSD6_PEX_PWR_EN")
		)
		(pad "6" smd rect
			(at -2.925064 -0.32512 270)
			(size 0.4064 1.3716)
			(layers "F.Cu" "F.Mask" "F.Paste")
			(net "RST_PEX_SSD6_PERST_N")
		)
		(pad "7" smd rect
			(at -2.925064 0.32512 270)
			(size 0.4064 1.3716)
			(layers "F.Cu" "F.Mask" "F.Paste")
			(net "Net_1173")
		)
		(pad "8" smd rect
			(at -2.925064 0.975106 270)
			(size 0.4064 1.3716)
			(layers "F.Cu" "F.Mask" "F.Paste")
			(net "PRSNT_SSD7_FPGA_PCA9555_N")
		)
		(pad "9" smd rect
			(at -2.925064 1.625092 270)
			(size 0.4064 1.3716)
			(layers "F.Cu" "F.Mask" "F.Paste")
			(net "SSD7_PEX_PWR_EN")
		)
		(pad "10" smd rect
			(at -2.925064 2.275078 270)
			(size 0.4064 1.3716)
			(layers "F.Cu" "F.Mask" "F.Paste")
			(net "RST_PEX_SSD7_PERST_N")
		)
		(pad "11" smd rect
			(at -2.925064 2.925064 270)
			(size 0.4064 1.3716)
			(layers "F.Cu" "F.Mask" "F.Paste")
			(net "Net_1172")
		)
		(pad "12" smd rect
			(at -2.925064 3.674872 270)
			(size 0.6096 1.3716)
			(layers "F.Cu" "F.Mask" "F.Paste")
			(net "GND")
		)
		(pad "13" smd rect
			(at 2.925064 3.674872 270)
			(size 0.6096 1.3716)
			(layers "F.Cu" "F.Mask" "F.Paste")
			(net "PRSNT_NIC3_FPGA_PCA9555_N")
		)
		(pad "14" smd rect
			(at 2.925064 2.925064 270)
			(size 0.4064 1.3716)
			(layers "F.Cu" "F.Mask" "F.Paste")
			(net "NIC3_PEX_PWR_EN")
		)
		(pad "15" smd rect
			(at 2.925064 2.275078 270)
			(size 0.4064 1.3716)
			(layers "F.Cu" "F.Mask" "F.Paste")
			(net "RST_PEX_NIC3_PERST_N")
		)
		(pad "16" smd rect
			(at 2.925064 1.625092 270)
			(size 0.4064 1.3716)
			(layers "F.Cu" "F.Mask" "F.Paste")
			(net "Net_1174")
		)
		(pad "17" smd rect
			(at 2.925064 0.975106 270)
			(size 0.4064 1.3716)
			(layers "F.Cu" "F.Mask" "F.Paste")
			(net "Net_8980")
		)
		(pad "18" smd rect
			(at 2.925064 0.32512 270)
			(size 0.4064 1.3716)
			(layers "F.Cu" "F.Mask" "F.Paste")
			(net "Net_8979")
		)
		(pad "19" smd rect
			(at 2.925064 -0.32512 270)
			(size 0.4064 1.3716)
			(layers "F.Cu" "F.Mask" "F.Paste")
			(net "Net_8978")
		)
		(pad "20" smd rect
			(at 2.925064 -0.975106 270)
			(size 0.4064 1.3716)
			(layers "F.Cu" "F.Mask" "F.Paste")
			(net "Net_8977")
		)
		(pad "21" smd rect
			(at 2.925064 -1.625092 270)
			(size 0.4064 1.3716)
			(layers "F.Cu" "F.Mask" "F.Paste")
			(net "PCA9555_1_PEX1_A0")
		)
		(pad "22" smd rect
			(at 2.925064 -2.275078 270)
			(size 0.4064 1.3716)
			(layers "F.Cu" "F.Mask" "F.Paste")
			(net "SMB_PEX1_PCA9555_SCL")
		)
		(pad "23" smd rect
			(at 2.925064 -2.925064 270)
			(size 0.4064 1.3716)
			(layers "F.Cu" "F.Mask" "F.Paste")
			(net "SMB_PEX1_PCA9555_SDA")
		)
		(pad "24" smd rect
			(at 2.925064 -3.674872 270)
			(size 0.6096 1.3716)
			(layers "F.Cu" "F.Mask" "F.Paste")
			(net "P3V3_AUX")
		)
	)
	(footprint ""
		(layer "F.Cu")
		(at 430.961546 -147.99691 180)
		(property "Reference" "C643"
			(at 0 0 180)
			(layer "F.SilkS")
			(hide yes)
			(effects
				(font
					(size 1.27 1.27)
				)
			)
		)
		(property "Value" ""
			(at 0 0 180)
			(layer "F.Fab")
			(effects
				(font
					(size 1.27 1.27)
				)
			)
		)
		(duplicate_pad_numbers_are_jumpers no)
		(fp_line
			(start 0.299974 0.150114)
			(end -0.299974 0.150114)
			(stroke
				(width 0.1)
				(type default)
			)
			(layer "F.Fab")
		)
		(fp_line
			(start 0.299974 -0.150114)
			(end 0.299974 0.150114)
			(stroke
				(width 0.1)
				(type default)
			)
			(layer "F.Fab")
		)
		(fp_line
			(start -0.299974 0.150114)
			(end -0.299974 -0.150114)
			(stroke
				(width 0.1)
				(type default)
			)
			(layer "F.Fab")
		)
		(fp_line
			(start -0.299974 -0.150114)
			(end 0.299974 -0.150114)
			(stroke
				(width 0.1)
				(type default)
			)
			(layer "F.Fab")
		)
		(pad "1" smd rect
			(at -0.2667 0 180)
			(size 0.3048 0.381)
			(layers "F.Cu" "F.Mask" "F.Paste")
			(net "P5E_PEX3_STN0_TX_DN<11>")
		)
		(pad "2" smd rect
			(at 0.2667 0 180)
			(size 0.3048 0.381)
			(layers "F.Cu" "F.Mask" "F.Paste")
			(net "P5E_PEX3_STN0_TX_C_DN<11>")
		)
	)
)
